FILE_TYPE = MULTI_PHYS_TABLE;

PART 'PCA9555PW'

{========================================================================================}
:PACK_TYPE | VALUE       | MATERIAL | PART_NUMBER           = STANDARD         | LIFECYCLE        | PART_NUMBER        | JEDEC_TYPE  | CLASS | DESCRIPTION                  | HEIGHT   | COMPONENT_TYPE | LEAD_LENGTH | DFM_EXCLUSION ;
{========================================================================================}
 'SMLF'    | 'PCA9555PW' | 'IC'     | 'TMP_QAL009555K04'(!) = ''               | ''               | 'AL009555K04' |'TSSOP24'| 'IC'  | 'IC(24P) PCA9555PW(TSSOP)EP' | '.044IN' | 'SMALLSMT'     | ''          | ''           
 'SMLF'    | 'PCA9555PW' | 'EMPTY'  | 'TMP_QAL009555K04'(!) = ''               | ''               | 'AL009555K04' |'TSSOP24'| 'IO'  | 'IC(24P) PCA9555PW(TSSOP)EP' | '.044IN' | 'SMALLSMT'     | ''          | ''           
 'SMLF'    | 'PCA9555PW' | 'IC'     | 'QN-AL009555K04'(!)   = ''               | ''               | 'AL009555K04'   |'TSSOP24'| 'IC'  | 'IC(24P) PCA9555PW(TSSOP)EP' | '.044IN' | 'SMALLSMT'     | ''          | ''           
 'SMLF'    | 'PCA9555PW' | 'EMPTY'  | 'QN-AL009555K04'(!)   = ''               | ''               | 'AL009555K04'   |'TSSOP24'| 'IO'  | 'IC(24P) PCA9555PW(TSSOP)EP' | '.044IN' | 'SMALLSMT'     | ''          | ''           

END_PART

END.

